(kicad_pcb
	(version 20260206)
	(generator "pcbnew")
	(generator_version "10.0")
	(general
		(thickness 1.6)
		(legacy_teardrops no)
	)
	(paper "A4")
	(title_block
		(title "Bryce Canyon_F.DPB_16315-1-OCP.brd")
		(comment 1 "Bryce Canyon / footprints 766-772 of 2223")
	)
	(layers
		(0 "F.Cu" signal "TOP")
		(4 "In1.Cu" signal "L2GND")
		(6 "In2.Cu" signal "L3")
		(8 "In3.Cu" signal "L4GND")
		(10 "In4.Cu" signal "L5")
		(12 "In5.Cu" signal "L6VCC")
		(14 "In6.Cu" signal "L7VCC")
		(16 "In7.Cu" signal "L8")
		(18 "In8.Cu" signal "L9GND")
		(20 "In9.Cu" signal "L10")
		(22 "In10.Cu" signal "L11GND")
		(2 "B.Cu" signal "BOTTOM")
		(9 "F.Adhes" user "F.Adhesive")
		(11 "B.Adhes" user "B.Adhesive")
		(13 "F.Paste" user "Package Geometry/Pastemask Top")
		(15 "B.Paste" user "Package Geometry/Pastemask Bottom")
		(5 "F.SilkS" user "Ref Des/Silkscreen Top")
		(7 "B.SilkS" user "Ref Des/Silkscreen Bottom")
		(1 "F.Mask" user "Board Geometry/Soldermask Top")
		(3 "B.Mask" user "Board Geometry/Soldermask Bottom")
		(17 "Dwgs.User" user "User.Drawings")
		(19 "Cmts.User" user "User.Comments")
		(21 "Eco1.User" user "User.Eco1")
		(23 "Eco2.User" user "User.Eco2")
		(25 "Edge.Cuts" user "Board Geometry/Outline")
		(27 "Margin" user)
		(31 "F.CrtYd" user "Package Geometry/Place Bound Top")
		(29 "B.CrtYd" user "Package Geometry/Place Bound Bottom")
		(35 "F.Fab" user "Ref Des/Assembly Top")
		(33 "B.Fab" user "Ref Des/Assembly Bottom")
	)
	(footprint ""
		(layer "F.Cu")
		(at 395.20495 -275.252942 -90)
		(property "Reference" "Q49"
			(at 0 0 270)
			(layer "F.SilkS")
			(hide yes)
			(effects
				(font
					(size 1.27 1.27)
				)
			)
		)
		(property "Value" "2N7002KDW-GP"
			(at -2.3622 -8.2042 270)
			(unlocked yes)
			(layer "F.Fab")
			(hide yes)
			(effects
				(font
					(size 1.016 1.016)
					(thickness 0.1524)
				)
			)
		)
		(property "Device Type" "SOT-363H44"
			(at -2.3622 -10.1092 270)
			(unlocked yes)
			(layer "F.Fab")
			(hide yes)
			(effects
				(font
					(size 1.016 1.016)
					(thickness 0.1524)
				)
			)
		)
		(duplicate_pad_numbers_are_jumpers no)
		(fp_line
			(start -1.4478 1.7018)
			(end 1.4478 1.7018)
			(stroke
				(width 0.1524)
				(type default)
			)
			(layer "F.SilkS")
		)
		(fp_line
			(start 1.4478 1.7018)
			(end 1.4478 -1.7018)
			(stroke
				(width 0.1524)
				(type default)
			)
			(layer "F.SilkS")
		)
		(fp_line
			(start -1.27 1.524)
			(end -1.27 0.6604)
			(stroke
				(width 0.4826)
				(type default)
			)
			(layer "F.SilkS")
		)
		(fp_line
			(start -1.4478 -1.7018)
			(end -1.4478 1.7018)
			(stroke
				(width 0.1524)
				(type default)
			)
			(layer "F.SilkS")
		)
		(fp_line
			(start 1.4478 -1.7018)
			(end -1.4478 -1.7018)
			(stroke
				(width 0.1524)
				(type default)
			)
			(layer "F.SilkS")
		)
		(fp_poly
			(pts
				(xy -1.524 -1.778) (xy 1.524 -1.778) (xy 1.524 1.778) (xy -1.524 1.778)
			)
			(stroke
				(width 0)
				(type default)
			)
			(fill no)
			(layer "F.CrtYd")
		)
		(fp_poly
			(pts
				(xy -1.524 -1.778) (xy 1.524 -1.778) (xy 1.524 1.778) (xy -1.524 1.778)
			)
			(stroke
				(width 0)
				(type default)
			)
			(fill no)
			(layer "F.Fab")
		)
		(pad "1" smd rect
			(at -0.65024 0.9398 270)
			(size 0.4064 1.016)
			(layers "F.Cu" "F.Mask" "F.Paste")
			(net "GND")
		)
		(pad "2" smd rect
			(at 0 0.9398 270)
			(size 0.4064 1.016)
			(layers "F.Cu" "F.Mask" "F.Paste")
			(net "SW_PWR_R_HDD8")
		)
		(pad "3" smd rect
			(at 0.65024 0.9398 270)
			(size 0.4064 1.016)
			(layers "F.Cu" "F.Mask" "F.Paste")
			(net "SW_HDD_P8")
		)
		(pad "4" smd rect
			(at 0.65024 -0.9398 270)
			(size 0.4064 1.016)
			(layers "F.Cu" "F.Mask" "F.Paste")
			(net "GND")
		)
		(pad "5" smd rect
			(at 0 -0.9398 270)
			(size 0.4064 1.016)
			(layers "F.Cu" "F.Mask" "F.Paste")
			(net "SW_HDD_G8")
		)
		(pad "6" smd rect
			(at -0.65024 -0.9398 270)
			(size 0.4064 1.016)
			(layers "F.Cu" "F.Mask" "F.Paste")
			(net "SW_HDD_R8")
		)
	)
	(footprint ""
		(layer "F.Cu")
		(at 237.988856 -343.309448 180)
		(property "Reference" "R186"
			(at 0 0 180)
			(layer "F.SilkS")
			(hide yes)
			(effects
				(font
					(size 1.27 1.27)
				)
			)
		)
		(property "Value" "16K2R2F-GP"
			(at 0.064008 -3.993896 180)
			(unlocked yes)
			(layer "F.Fab")
			(hide yes)
			(effects
				(font
					(size 1.016 1.016)
					(thickness 0.1524)
				)
			)
		)
		(property "Device Type" "R402H16"
			(at 0.064008 -5.517896 180)
			(unlocked yes)
			(layer "F.Fab")
			(hide yes)
			(effects
				(font
					(size 1.016 1.016)
					(thickness 0.1524)
				)
			)
		)
		(duplicate_pad_numbers_are_jumpers no)
		(fp_line
			(start 0.508 -0.9398)
			(end -0.508 -0.9398)
			(stroke
				(width 0.1524)
				(type default)
			)
			(layer "F.SilkS")
		)
		(fp_line
			(start -0.508 -0.9398)
			(end -0.508 0.9398)
			(stroke
				(width 0.1524)
				(type default)
			)
			(layer "F.SilkS")
		)
		(fp_rect
			(start -0.508 0.9398)
			(end 0.508 -0.9398)
			(stroke
				(width 0)
				(type default)
			)
			(fill no)
			(layer "F.CrtYd")
		)
		(fp_rect
			(start -0.508 0.9398)
			(end 0.508 -0.9398)
			(stroke
				(width 0)
				(type default)
			)
			(fill no)
			(layer "F.Fab")
		)
		(pad "1" smd custom
			(at 0 -0.4445 180)
			(size 0.1397 0.1397)
			(layers "F.Cu" "F.Mask" "F.Paste")
			(net "P5V_A_4")
			(options
				(clearance outline)
				(anchor circle)
			)
			(primitives
				(gr_poly
					(pts
						(arc
							(start -0.1778 -0.2794)
							(mid -0.249642 -0.249642)
							(end -0.2794 -0.1778)
						)
						(arc
							(start -0.2794 0.1778)
							(mid -0.249642 0.249642)
							(end -0.1778 0.2794)
						)
						(arc
							(start 0.1778 0.2794)
							(mid 0.249642 0.249642)
							(end 0.2794 0.1778)
						)
						(arc
							(start 0.2794 -0.1778)
							(mid 0.249642 -0.249642)
							(end 0.1778 -0.2794)
						)
					)
					(width 0)
					(fill yes)
				)
			)
		)
		(pad "2" smd custom
			(at 0 0.4445 180)
			(size 0.1397 0.1397)
			(layers "F.Cu" "F.Mask" "F.Paste")
			(net "P5V_A_4_SENSE")
			(options
				(clearance outline)
				(anchor circle)
			)
			(primitives
				(gr_poly
					(pts
						(arc
							(start -0.1778 -0.2794)
							(mid -0.249642 -0.249642)
							(end -0.2794 -0.1778)
						)
						(arc
							(start -0.2794 0.1778)
							(mid -0.249642 0.249642)
							(end -0.1778 0.2794)
						)
						(arc
							(start 0.1778 0.2794)
							(mid 0.249642 0.249642)
							(end 0.2794 0.1778)
						)
						(arc
							(start 0.2794 -0.1778)
							(mid 0.249642 -0.249642)
							(end 0.1778 -0.2794)
						)
					)
					(width 0)
					(fill yes)
				)
			)
		)
	)
	(footprint ""
		(layer "F.Cu")
		(at 266.192 -112.268 -90)
		(property "Reference" "R623"
			(at 0 0 270)
			(layer "F.SilkS")
			(hide yes)
			(effects
				(font
					(size 1.27 1.27)
				)
			)
		)
		(property "Value" "4K7R2F-GP"
			(at 0.064008 -3.993896 270)
			(unlocked yes)
			(layer "F.Fab")
			(hide yes)
			(effects
				(font
					(size 1.016 1.016)
					(thickness 0.1524)
				)
			)
		)
		(property "Device Type" "R402H16"
			(at 0.064008 -5.517896 270)
			(unlocked yes)
			(layer "F.Fab")
			(hide yes)
			(effects
				(font
					(size 1.016 1.016)
					(thickness 0.1524)
				)
			)
		)
		(duplicate_pad_numbers_are_jumpers no)
		(fp_line
			(start -0.508 -0.9398)
			(end -0.508 0.9398)
			(stroke
				(width 0.1524)
				(type default)
			)
			(layer "F.SilkS")
		)
		(fp_line
			(start 0.508 -0.9398)
			(end -0.508 -0.9398)
			(stroke
				(width 0.1524)
				(type default)
			)
			(layer "F.SilkS")
		)
		(fp_rect
			(start -0.508 0.9398)
			(end 0.508 -0.9398)
			(stroke
				(width 0)
				(type default)
			)
			(fill no)
			(layer "F.CrtYd")
		)
		(fp_rect
			(start -0.508 0.9398)
			(end 0.508 -0.9398)
			(stroke
				(width 0)
				(type default)
			)
			(fill no)
			(layer "F.Fab")
		)
		(pad "1" smd custom
			(at 0 -0.4445 270)
			(size 0.1397 0.1397)
			(layers "F.Cu" "F.Mask" "F.Paste")
			(net "COMP_B_BMC_B_ALERT_N")
			(options
				(clearance outline)
				(anchor circle)
			)
			(primitives
				(gr_poly
					(pts
						(arc
							(start -0.1778 -0.2794)
							(mid -0.249642 -0.249642)
							(end -0.2794 -0.1778)
						)
						(arc
							(start -0.2794 0.1778)
							(mid -0.249642 0.249642)
							(end -0.1778 0.2794)
						)
						(arc
							(start 0.1778 0.2794)
							(mid 0.249642 0.249642)
							(end 0.2794 0.1778)
						)
						(arc
							(start 0.2794 -0.1778)
							(mid 0.249642 -0.249642)
							(end 0.1778 -0.2794)
						)
					)
					(width 0)
					(fill yes)
				)
			)
		)
		(pad "2" smd custom
			(at 0 0.4445 270)
			(size 0.1397 0.1397)
			(layers "F.Cu" "F.Mask" "F.Paste")
			(net "P3V3_STBY_B")
			(options
				(clearance outline)
				(anchor circle)
			)
			(primitives
				(gr_poly
					(pts
						(arc
							(start -0.1778 -0.2794)
							(mid -0.249642 -0.249642)
							(end -0.2794 -0.1778)
						)
						(arc
							(start -0.2794 0.1778)
							(mid -0.249642 0.249642)
							(end -0.1778 0.2794)
						)
						(arc
							(start 0.1778 0.2794)
							(mid 0.249642 0.249642)
							(end 0.2794 0.1778)
						)
						(arc
							(start 0.2794 -0.1778)
							(mid 0.249642 -0.249642)
							(end 0.1778 -0.2794)
						)
					)
					(width 0)
					(fill yes)
				)
			)
		)
	)
	(footprint ""
		(layer "F.Cu")
		(at 130.447796 -62.143894 -90)
		(property "Reference" "R751"
			(at 0 0 270)
			(layer "F.SilkS")
			(hide yes)
			(effects
				(font
					(size 1.27 1.27)
				)
			)
		)
		(property "Value" "10KR2F-2-GP"
			(at 0.064008 -3.993896 270)
			(unlocked yes)
			(layer "F.Fab")
			(hide yes)
			(effects
				(font
					(size 1.016 1.016)
					(thickness 0.1524)
				)
			)
		)
		(property "Device Type" "R402H16"
			(at 0.064008 -5.517896 270)
			(unlocked yes)
			(layer "F.Fab")
			(hide yes)
			(effects
				(font
					(size 1.016 1.016)
					(thickness 0.1524)
				)
			)
		)
		(duplicate_pad_numbers_are_jumpers no)
		(fp_line
			(start -0.508 -0.9398)
			(end -0.508 0.9398)
			(stroke
				(width 0.1524)
				(type default)
			)
			(layer "F.SilkS")
		)
		(fp_line
			(start 0.508 -0.9398)
			(end -0.508 -0.9398)
			(stroke
				(width 0.1524)
				(type default)
			)
			(layer "F.SilkS")
		)
		(fp_rect
			(start -0.508 0.9398)
			(end 0.508 -0.9398)
			(stroke
				(width 0)
				(type default)
			)
			(fill no)
			(layer "F.CrtYd")
		)
		(fp_rect
			(start -0.508 0.9398)
			(end 0.508 -0.9398)
			(stroke
				(width 0)
				(type default)
			)
			(fill no)
			(layer "F.Fab")
		)
		(pad "1" smd custom
			(at 0 -0.4445 270)
			(size 0.1397 0.1397)
			(layers "F.Cu" "F.Mask" "F.Paste")
			(net "P3V3_STBY_A")
			(options
				(clearance outline)
				(anchor circle)
			)
			(primitives
				(gr_poly
					(pts
						(arc
							(start -0.1778 -0.2794)
							(mid -0.249642 -0.249642)
							(end -0.2794 -0.1778)
						)
						(arc
							(start -0.2794 0.1778)
							(mid -0.249642 0.249642)
							(end -0.1778 0.2794)
						)
						(arc
							(start 0.1778 0.2794)
							(mid 0.249642 0.249642)
							(end 0.2794 0.1778)
						)
						(arc
							(start 0.2794 -0.1778)
							(mid 0.249642 -0.249642)
							(end 0.1778 -0.2794)
						)
					)
					(width 0)
					(fill yes)
				)
			)
		)
		(pad "2" smd custom
			(at 0 0.4445 270)
			(size 0.1397 0.1397)
			(layers "F.Cu" "F.Mask" "F.Paste")
			(net "HDD_PRSNT_27")
			(options
				(clearance outline)
				(anchor circle)
			)
			(primitives
				(gr_poly
					(pts
						(arc
							(start -0.1778 -0.2794)
							(mid -0.249642 -0.249642)
							(end -0.2794 -0.1778)
						)
						(arc
							(start -0.2794 0.1778)
							(mid -0.249642 0.249642)
							(end -0.1778 0.2794)
						)
						(arc
							(start 0.1778 0.2794)
							(mid 0.249642 0.249642)
							(end 0.2794 0.1778)
						)
						(arc
							(start 0.2794 -0.1778)
							(mid 0.249642 -0.249642)
							(end 0.1778 -0.2794)
						)
					)
					(width 0)
					(fill yes)
				)
			)
		)
	)
	(footprint ""
		(layer "F.Cu")
		(at 96.324928 -207.79994)
		(property "Reference" ""
			(at 0 0 0)
			(layer "F.SilkS")
			(hide yes)
			(effects
				(font
					(size 1.27 1.27)
				)
			)
		)
		(property "Value" "*"
			(at -8.398764 -8.057642 0)
			(unlocked yes)
			(layer "F.Fab")
			(hide yes)
			(effects
				(font
					(size 1.016 1.016)
					(thickness 0.1524)
				)
			)
		)
		(duplicate_pad_numbers_are_jumpers no)
		(fp_poly
			(pts
				(arc
					(start 7.3152 0)
					(mid 0 7.3152)
					(end -7.3152 0)
				)
				(arc
					(start -7.3152 -5.9944)
					(mid 0 -13.3096)
					(end 7.3152 -5.9944)
				)
			)
			(stroke
				(width 0)
				(type default)
			)
			(fill no)
			(layer "B.CrtYd")
		)
		(fp_poly
			(pts
				(arc
					(start 7.3152 0)
					(mid 0 7.3152)
					(end -7.3152 0)
				)
				(arc
					(start -7.3152 -5.9944)
					(mid 0 -13.3096)
					(end 7.3152 -5.9944)
				)
			)
			(stroke
				(width 0)
				(type default)
			)
			(fill no)
			(layer "F.CrtYd")
		)
		(fp_poly
			(pts
				(arc
					(start 7.3152 0)
					(mid 0 7.3152)
					(end -7.3152 0)
				)
				(arc
					(start -7.3152 -5.9944)
					(mid 0 -13.3096)
					(end 7.3152 -5.9944)
				)
			)
			(stroke
				(width 0)
				(type default)
			)
			(fill no)
			(layer "B.Fab")
		)
		(fp_poly
			(pts
				(arc
					(start 7.3152 0)
					(mid 0 7.3152)
					(end -7.3152 0)
				)
				(arc
					(start -7.3152 -5.9944)
					(mid 0 -13.3096)
					(end 7.3152 -5.9944)
				)
			)
			(stroke
				(width 0)
				(type default)
			)
			(fill no)
			(layer "F.Fab")
		)
		(pad "1" thru_hole oval
			(at 0 0)
			(size 14.0208 20.0152)
			(drill 0.0254
				(offset 0 -2.9972)
			)
			(layers "*.Cu" "*.Mask")
			(remove_unused_layers no)
			(net "Net_104")
			(clearance -1.002284)
			(thermal_gap 0.1524)
			(padstack
				(mode front_inner_back)
				(layer "Inner"
					(shape custom)
					(size 2.928012 2.928012)
					(options
						(anchor circle)
					)
					(primitives
						(gr_poly
							(pts
								(arc
									(start 4.571746 -2.084324)
									(mid 0.000333 7.430372)
									(end -4.571492 -2.084324)
								)
								(arc
									(start -4.571492 -2.084324)
									(mid -3.570296 -3.611977)
									(end -2.875026 -5.30098)
								)
								(arc
									(start -2.875026 -5.30098)
									(mid 0.000217 -7.43089)
									(end 2.87528 -5.30098)
								)
								(arc
									(start 2.87528 -5.30098)
									(mid 3.570511 -3.611956)
									(end 4.571746 -2.084324)
								)
							)
							(width 0)
							(fill yes)
						)
					)
					(clearance 0.1524)
				)
				(layer "B.Cu"
					(shape oval)
					(size 14.0208 20.0152)
					(offset 0 -2.9972)
					(clearance -1.002284)
				)
			)
		)
		(zone
			(layers "F.Cu" "B.Cu" "In1.Cu" "In2.Cu" "In3.Cu" "In4.Cu" "In5.Cu" "In6.Cu"
				"In7.Cu" "In8.Cu" "In9.Cu" "In10.Cu"
			)
			(hatch none 0.5)
			(connect_pads
				(clearance 0)
			)
			(min_thickness 0.25)
			(keepout
				(tracks not_allowed)
				(vias allowed)
				(pads allowed)
				(copperpour not_allowed)
				(footprints allowed)
			)
			(placement
				(enabled no)
				(sheetname "")
			)
			(fill
				(thermal_gap 0.5)
				(thermal_bridge_width 0.5)
				(island_removal_mode 0)
			)
			(polygon
				(pts
					(arc
						(start 89.314528 -213.79434)
						(mid 96.324928 -220.80474)
						(end 103.335328 -213.79434)
					)
					(arc
						(start 103.335328 -207.79994)
						(mid 96.324928 -200.78954)
						(end 89.314528 -207.79994)
					)
				)
			)
		)
	)
	(footprint ""
		(layer "F.Cu")
		(at 363.909102 -65.826894 180)
		(property "Reference" "C444"
			(at 0 0 180)
			(layer "F.SilkS")
			(hide yes)
			(effects
				(font
					(size 1.27 1.27)
				)
			)
		)
		(property "Value" "SC10U16V6KX-2GP"
			(at -0.0762 -5.1308 180)
			(unlocked yes)
			(layer "F.Fab")
			(hide yes)
			(effects
				(font
					(size 1.016 1.016)
					(thickness 0.1524)
				)
			)
		)
		(property "Device Type" "C1206H71"
			(at -0.127 -6.6548 180)
			(unlocked yes)
			(layer "F.Fab")
			(hide yes)
			(effects
				(font
					(size 1.016 1.016)
					(thickness 0.1524)
				)
			)
		)
		(duplicate_pad_numbers_are_jumpers no)
		(fp_line
			(start 1.016 2.2352)
			(end -1.016 2.2352)
			(stroke
				(width 0.1524)
				(type default)
			)
			(layer "F.SilkS")
		)
		(fp_line
			(start 1.016 0.8382)
			(end 1.016 2.2352)
			(stroke
				(width 0.1524)
				(type default)
			)
			(layer "F.SilkS")
		)
		(fp_line
			(start 1.016 -2.2352)
			(end 1.016 -0.8382)
			(stroke
				(width 0.1524)
				(type default)
			)
			(layer "F.SilkS")
		)
		(fp_line
			(start -1.016 2.2352)
			(end -1.016 0.8382)
			(stroke
				(width 0.1524)
				(type default)
			)
			(layer "F.SilkS")
		)
		(fp_line
			(start -1.016 -0.8382)
			(end -1.016 -2.2352)
			(stroke
				(width 0.1524)
				(type default)
			)
			(layer "F.SilkS")
		)
		(fp_line
			(start -1.016 -2.2352)
			(end 1.016 -2.2352)
			(stroke
				(width 0.1524)
				(type default)
			)
			(layer "F.SilkS")
		)
		(fp_rect
			(start -1.0922 2.3114)
			(end 1.0922 -2.3114)
			(stroke
				(width 0)
				(type default)
			)
			(fill no)
			(layer "F.CrtYd")
		)
		(fp_poly
			(pts
				(xy 1.0922 -2.3114) (xy 1.0922 2.3114) (xy -1.0922 2.3114) (xy -1.0922 -2.3114)
			)
			(stroke
				(width 0)
				(type default)
			)
			(fill no)
			(layer "F.Fab")
		)
		(pad "1" smd rect
			(at 0 -1.397 180)
			(size 1.651 1.27)
			(layers "F.Cu" "F.Mask" "F.Paste")
			(net "P5V_HDD31")
		)
		(pad "2" smd rect
			(at 0 1.397 180)
			(size 1.651 1.27)
			(layers "F.Cu" "F.Mask" "F.Paste")
			(net "GND")
		)
	)
	(footprint ""
		(layer "F.Cu")
		(at 427.390052 -49.596294 90)
		(property "Reference" "C477"
			(at 0 0 90)
			(layer "F.SilkS")
			(hide yes)
			(effects
				(font
					(size 1.27 1.27)
				)
			)
		)
		(property "Value" "SCD033U25V2KX-GP"
			(at 1.1811 -2.7051 90)
			(unlocked yes)
			(layer "F.Fab")
			(hide yes)
			(effects
				(font
					(size 1.016 1.016)
					(thickness 0.1524)
				)
			)
		)
		(property "Device Type" "C402H22"
			(at 1.1811 -4.2291 90)
			(unlocked yes)
			(layer "F.Fab")
			(hide yes)
			(effects
				(font
					(size 1.016 1.016)
					(thickness 0.1524)
				)
			)
		)
		(duplicate_pad_numbers_are_jumpers no)
		(fp_rect
			(start -0.4318 0.9525)
			(end 0.4318 -0.9525)
			(stroke
				(width 0)
				(type default)
			)
			(fill no)
			(layer "F.CrtYd")
		)
		(fp_rect
			(start -0.4318 0.9525)
			(end 0.4318 -0.9525)
			(stroke
				(width 0)
				(type default)
			)
			(fill no)
			(layer "F.Fab")
		)
		(pad "1" smd custom
			(at 0 -0.4445 90)
			(size 0.1524 0.1524)
			(layers "F.Cu" "F.Mask" "F.Paste")
			(net "SW_HDD_P33")
			(options
				(clearance outline)
				(anchor circle)
			)
			(primitives
				(gr_poly
					(pts
						(arc
							(start 0.3048 -0.2032)
							(mid 0.275042 -0.275042)
							(end 0.2032 -0.3048)
						)
						(arc
							(start -0.2032 -0.3048)
							(mid -0.275042 -0.275042)
							(end -0.3048 -0.2032)
						)
						(arc
							(start -0.3048 0.2032)
							(mid -0.275042 0.275042)
							(end -0.2032 0.3048)
						)
						(arc
							(start 0.2032 0.3048)
							(mid 0.275042 0.275042)
							(end 0.3048 0.2032)
						)
					)
					(width 0)
					(fill yes)
				)
			)
		)
		(pad "2" smd custom
			(at 0 0.4445 90)
			(size 0.1524 0.1524)
			(layers "F.Cu" "F.Mask" "F.Paste")
			(net "GND")
			(options
				(clearance outline)
				(anchor circle)
			)
			(primitives
				(gr_poly
					(pts
						(arc
							(start 0.3048 -0.2032)
							(mid 0.275042 -0.275042)
							(end 0.2032 -0.3048)
						)
						(arc
							(start -0.2032 -0.3048)
							(mid -0.275042 -0.275042)
							(end -0.3048 -0.2032)
						)
						(arc
							(start -0.3048 0.2032)
							(mid -0.275042 0.275042)
							(end -0.2032 0.3048)
						)
						(arc
							(start 0.2032 0.3048)
							(mid 0.275042 0.275042)
							(end 0.3048 0.2032)
						)
					)
					(width 0)
					(fill yes)
				)
			)
		)
	)
)
